#ISCELL
  pure_quanta quanta_title_block_c *
  *
#CELL
  pure_quanta q_cap *
  page69_i1
#CELL
  pure_quanta q_cap *
  page69_i10
#ISCELL
  pure_quanta_power universal_gnd *
  page69_i100
#CELL
  pure_quanta q_cap *
  page69_i101
#CELL
  pure_quanta q_cap *
  page69_i102
#ISCELL
  pure_quanta_power universal_power *
  page69_i103
#CELL
  pure_quanta q_cap *
  page69_i104
#ISCELL
  pure_quanta_power universal_gnd *
  page69_i105
#CELL
  pure_quanta q_cap *
  page69_i106
#ISCELL
  pure_quanta_power universal_power *
  page69_i107
#CELL
  pure_quanta q_cap *
  page69_i108
#ISCELL
  pure_quanta_power universal_power *
  page69_i109
#CELL
  pure_quanta q_cap *
  page69_i11
#ISCELL
  pure_quanta_power universal_gnd *
  page69_i110
#CELL
  pure_quanta q_cap *
  page69_i111
#CELL
  pure_quanta q_cap *
  page69_i112
#CELL
  pure_quanta q_cap *
  page69_i113
#CELL
  pure_quanta q_cap *
  page69_i114
#CELL
  pure_quanta q_cap *
  page69_i115
#CELL
  pure_quanta q_cap *
  page69_i116
#CELL
  pure_quanta q_cap *
  page69_i117
#CELL
  pure_quanta q_cap *
  page69_i118
#CELL
  pure_quanta q_cap *
  page69_i119
#ISCELL
  pure_quanta_power universal_power *
  page69_i12
#CELL
  pure_quanta q_cap *
  page69_i120
#CELL
  pure_quanta q_cap *
  page69_i121
#CELL
  pure_quanta q_cap *
  page69_i122
#CELL
  pure_quanta q_cap *
  page69_i123
#CELL
  pure_quanta q_cap *
  page69_i124
#CELL
  pure_quanta q_cap *
  page69_i125
#CELL
  pure_quanta q_cap *
  page69_i126
#CELL
  pure_quanta q_cap *
  page69_i127
#ISCELL
  pure_quanta_power universal_gnd *
  page69_i128
#CELL
  pure_quanta q_cap *
  page69_i129
#CELL
  pure_quanta q_cap *
  page69_i13
#CELL
  pure_quanta q_cap *
  page69_i130
#CELL
  pure_quanta q_cap *
  page69_i131
#CELL
  pure_quanta q_cap *
  page69_i132
#CELL
  pure_quanta q_cap *
  page69_i133
#CELL
  pure_quanta q_cap *
  page69_i134
#CELL
  pure_quanta q_cap *
  page69_i135
#CELL
  pure_quanta q_cap *
  page69_i136
#ISCELL
  pure_quanta_power universal_gnd *
  page69_i137
#CELL
  pure_quanta q_cap *
  page69_i138
#CELL
  pure_quanta q_cap *
  page69_i139
#ISCELL
  pure_quanta_power universal_power *
  page69_i14
#CELL
  pure_quanta q_cap *
  page69_i140
#ISCELL
  pure_quanta_power universal_gnd *
  page69_i141
#CELL
  pure_quanta q_cap *
  page69_i142
#CELL
  pure_quanta q_cap *
  page69_i143
#CELL
  pure_quanta q_cap *
  page69_i144
#CELL
  pure_quanta q_cap *
  page69_i145
#CELL
  pure_quanta q_cap *
  page69_i146
#CELL
  pure_quanta q_cap *
  page69_i147
#ISCELL
  pure_quanta_power universal_gnd *
  page69_i148
#CELL
  pure_quanta q_cap *
  page69_i149
#CELL
  pure_quanta q_cap *
  page69_i15
#ISCELL
  pure_quanta_power universal_gnd *
  page69_i150
#CELL
  pure_quanta q_cap *
  page69_i151
#CELL
  pure_quanta q_cap *
  page69_i152
#CELL
  pure_quanta q_cap *
  page69_i153
#CELL
  pure_quanta q_cap *
  page69_i154
#CELL
  pure_quanta q_cap *
  page69_i155
#CELL
  pure_quanta q_cap *
  page69_i156
#CELL
  pure_quanta q_cap *
  page69_i157
#CELL
  pure_quanta q_cap *
  page69_i158
#CELL
  pure_quanta q_cap *
  page69_i159
#CELL
  pure_quanta q_cap *
  page69_i16
#CELL
  pure_quanta q_cap *
  page69_i160
#CELL
  pure_quanta q_cap *
  page69_i161
#CELL
  pure_quanta q_cap *
  page69_i162
#CELL
  pure_quanta q_cap *
  page69_i163
#CELL
  pure_quanta q_cap *
  page69_i164
#CELL
  pure_quanta q_cap *
  page69_i165
#CELL
  pure_quanta q_cap *
  page69_i166
#CELL
  pure_quanta q_cap *
  page69_i167
#CELL
  pure_quanta q_cap *
  page69_i168
#CELL
  pure_quanta q_cap *
  page69_i169
#ISCELL
  pure_quanta_power universal_power *
  page69_i17
#CELL
  pure_quanta q_cap *
  page69_i170
#ISCELL
  pure_quanta_power universal_gnd *
  page69_i171
#CELL
  pure_quanta q_cap *
  page69_i172
#CELL
  pure_quanta q_cap *
  page69_i173
#ISCELL
  pure_quanta_power universal_gnd *
  page69_i174
#CELL
  pure_quanta q_cap *
  page69_i175
#CELL
  pure_quanta q_cap *
  page69_i18
#CELL
  pure_quanta q_cap *
  page69_i19
#ISCELL
  pure_quanta_power universal_power *
  page69_i2
#CELL
  pure_quanta q_cap *
  page69_i20
#ISCELL
  pure_quanta_power universal_power *
  page69_i21
#CELL
  pure_quanta q_cap *
  page69_i22
#ISCELL
  pure_quanta_power universal_power *
  page69_i23
#CELL
  pure_quanta q_cap *
  page69_i24
#CELL
  pure_quanta q_cap *
  page69_i25
#CELL
  pure_quanta q_cap *
  page69_i26
#CELL
  pure_quanta q_cap *
  page69_i27
#CELL
  pure_quanta q_cap *
  page69_i28
#CELL
  pure_quanta q_cap *
  page69_i29
#CELL
  pure_quanta q_cap *
  page69_i3
#CELL
  pure_quanta q_cap *
  page69_i30
#CELL
  pure_quanta q_cap *
  page69_i31
#ISCELL
  pure_quanta_power universal_gnd *
  page69_i32
#CELL
  pure_quanta q_cap *
  page69_i33
#CELL
  pure_quanta q_cap *
  page69_i34
#CELL
  pure_quanta q_cap *
  page69_i35
#CELL
  pure_quanta q_cap *
  page69_i36
#CELL
  pure_quanta q_cap *
  page69_i37
#CELL
  pure_quanta q_cap *
  page69_i38
#CELL
  pure_quanta q_cap *
  page69_i39
#CELL
  pure_quanta q_cap *
  page69_i4
#CELL
  pure_quanta q_cap *
  page69_i40
#CELL
  pure_quanta q_cap *
  page69_i41
#CELL
  pure_quanta q_cap *
  page69_i42
#CELL
  pure_quanta q_cap *
  page69_i43
#CELL
  pure_quanta q_cap *
  page69_i44
#CELL
  pure_quanta q_cap *
  page69_i45
#CELL
  pure_quanta q_cap *
  page69_i46
#CELL
  pure_quanta q_cap *
  page69_i47
#CELL
  pure_quanta q_cap *
  page69_i48
#CELL
  pure_quanta q_cap *
  page69_i49
#ISCELL
  pure_quanta_power universal_power *
  page69_i5
#CELL
  pure_quanta q_cap *
  page69_i50
#CELL
  pure_quanta q_cap *
  page69_i51
#CELL
  pure_quanta q_cap *
  page69_i52
#CELL
  pure_quanta q_cap *
  page69_i53
#ISCELL
  pure_quanta_power universal_power *
  page69_i54
#ISCELL
  pure_quanta_power universal_gnd *
  page69_i55
#CELL
  pure_quanta q_cap *
  page69_i56
#ISCELL
  pure_quanta_power universal_gnd *
  page69_i57
#CELL
  pure_quanta q_cap *
  page69_i58
#ISCELL
  pure_quanta_power universal_power *
  page69_i59
#CELL
  pure_quanta q_cap *
  page69_i6
#CELL
  pure_quanta q_cap *
  page69_i60
#CELL
  pure_quanta q_cap *
  page69_i61
#CELL
  pure_quanta q_cap *
  page69_i62
#CELL
  pure_quanta q_cap *
  page69_i63
#CELL
  pure_quanta q_cap *
  page69_i64
#CELL
  pure_quanta q_cap *
  page69_i65
#CELL
  pure_quanta q_cap *
  page69_i66
#CELL
  pure_quanta q_cap *
  page69_i67
#ISCELL
  pure_quanta_power universal_gnd *
  page69_i68
#CELL
  pure_quanta q_cap *
  page69_i69
#CELL
  pure_quanta q_cap *
  page69_i7
#ISCELL
  pure_quanta_power universal_power *
  page69_i70
#CELL
  pure_quanta q_cap *
  page69_i71
#ISCELL
  pure_quanta_power universal_power *
  page69_i72
#ISCELL
  pure_quanta_power universal_gnd *
  page69_i73
#CELL
  pure_quanta q_cap *
  page69_i74
#ISCELL
  pure_quanta_power universal_gnd *
  page69_i75
#CELL
  pure_quanta q_cap *
  page69_i76
#ISCELL
  pure_quanta_power universal_power *
  page69_i77
#CELL
  pure_quanta q_cap *
  page69_i78
#CELL
  pure_quanta q_cap *
  page69_i79
#ISCELL
  pure_quanta_power universal_power *
  page69_i8
#CELL
  pure_quanta q_cap *
  page69_i80
#CELL
  pure_quanta q_cap *
  page69_i81
#CELL
  pure_quanta q_cap *
  page69_i82
#CELL
  pure_quanta q_cap *
  page69_i83
#CELL
  pure_quanta q_cap *
  page69_i84
#CELL
  pure_quanta q_cap *
  page69_i85
#CELL
  pure_quanta q_cap *
  page69_i86
#CELL
  pure_quanta q_cap *
  page69_i87
#CELL
  pure_quanta q_cap *
  page69_i88
#CELL
  pure_quanta q_cap *
  page69_i89
#CELL
  pure_quanta q_cap *
  page69_i9
#CELL
  pure_quanta q_cap *
  page69_i90
#CELL
  pure_quanta q_cap *
  page69_i91
#CELL
  pure_quanta q_cap *
  page69_i92
#CELL
  pure_quanta q_cap *
  page69_i93
#CELL
  pure_quanta q_cap *
  page69_i94
#CELL
  pure_quanta q_cap *
  page69_i95
#CELL
  pure_quanta q_cap *
  page69_i96
#CELL
  pure_quanta q_cap *
  page69_i97
#CELL
  pure_quanta q_cap *
  page69_i98
#CELL
  pure_quanta q_cap *
  page69_i99
